#ISCELL
  pure_quanta quanta_title_block_c *
  *
#ISCELL
  pure_quanta_power cad_note *
  *
#CELL
  pure_quanta genoa_sp5 *
  page13_i159
#ISCELL
  mstr_standard offpage *
  page13_i160
#ISCELL
  mstr_standard offpage *
  page13_i161
#ISCELL
  mstr_standard tap *
  page13_i162
#ISCELL
  mstr_standard tap *
  page13_i163
#ISCELL
  mstr_standard tap *
  page13_i164
#ISCELL
  mstr_standard tap *
  page13_i165
#ISCELL
  mstr_standard tap *
  page13_i166
#ISCELL
  mstr_standard tap *
  page13_i167
#ISCELL
  mstr_standard tap *
  page13_i168
#ISCELL
  mstr_standard tap *
  page13_i169
#ISCELL
  mstr_standard tap *
  page13_i170
#ISCELL
  mstr_standard tap *
  page13_i171
#ISCELL
  mstr_standard tap *
  page13_i172
#ISCELL
  mstr_standard tap *
  page13_i173
#ISCELL
  mstr_standard tap *
  page13_i174
#ISCELL
  mstr_standard tap *
  page13_i175
#ISCELL
  mstr_standard tap *
  page13_i176
#ISCELL
  mstr_standard tap *
  page13_i177
#ISCELL
  mstr_standard tap *
  page13_i178
#ISCELL
  mstr_standard tap *
  page13_i179
#ISCELL
  mstr_standard tap *
  page13_i180
#ISCELL
  mstr_standard tap *
  page13_i181
#ISCELL
  mstr_standard tap *
  page13_i182
#ISCELL
  mstr_standard tap *
  page13_i183
#ISCELL
  mstr_standard tap *
  page13_i184
#ISCELL
  mstr_standard tap *
  page13_i185
#ISCELL
  mstr_standard tap *
  page13_i186
#ISCELL
  mstr_standard tap *
  page13_i187
#ISCELL
  mstr_standard tap *
  page13_i188
#ISCELL
  mstr_standard tap *
  page13_i189
#ISCELL
  mstr_standard tap *
  page13_i190
#ISCELL
  mstr_standard tap *
  page13_i191
#ISCELL
  mstr_standard tap *
  page13_i192
#ISCELL
  mstr_standard tap *
  page13_i193
#ISCELL
  mstr_standard tap *
  page13_i194
#ISCELL
  mstr_standard tap *
  page13_i195
#ISCELL
  mstr_standard tap *
  page13_i196
#ISCELL
  mstr_standard offpage *
  page13_i197
#ISCELL
  mstr_standard tap *
  page13_i198
#ISCELL
  mstr_standard tap *
  page13_i199
#ISCELL
  mstr_standard tap *
  page13_i200
#ISCELL
  mstr_standard tap *
  page13_i201
#ISCELL
  mstr_standard tap *
  page13_i202
#ISCELL
  mstr_standard tap *
  page13_i203
#ISCELL
  mstr_standard tap *
  page13_i204
#ISCELL
  mstr_standard tap *
  page13_i205
#ISCELL
  mstr_standard tap *
  page13_i206
#ISCELL
  mstr_standard tap *
  page13_i207
#ISCELL
  mstr_standard tap *
  page13_i208
#ISCELL
  mstr_standard tap *
  page13_i209
#ISCELL
  mstr_standard tap *
  page13_i210
#ISCELL
  mstr_standard tap *
  page13_i211
#ISCELL
  mstr_standard tap *
  page13_i212
#ISCELL
  mstr_standard tap *
  page13_i213
#ISCELL
  mstr_standard tap *
  page13_i214
#ISCELL
  mstr_standard tap *
  page13_i215
#ISCELL
  mstr_standard tap *
  page13_i216
#ISCELL
  mstr_standard tap *
  page13_i217
#ISCELL
  mstr_standard tap *
  page13_i218
#ISCELL
  mstr_standard tap *
  page13_i219
#ISCELL
  mstr_standard tap *
  page13_i220
#ISCELL
  mstr_standard tap *
  page13_i221
#ISCELL
  mstr_standard tap *
  page13_i222
#ISCELL
  mstr_standard tap *
  page13_i223
#ISCELL
  mstr_standard tap *
  page13_i224
#ISCELL
  mstr_standard tap *
  page13_i225
#ISCELL
  mstr_standard tap *
  page13_i226
#ISCELL
  mstr_standard tap *
  page13_i227
#ISCELL
  mstr_standard tap *
  page13_i228
#ISCELL
  mstr_standard tap *
  page13_i229
#ISCELL
  mstr_standard tap *
  page13_i230
#ISCELL
  mstr_standard tap *
  page13_i231
#ISCELL
  mstr_standard tap *
  page13_i232
#ISCELL
  mstr_standard tap *
  page13_i233
#ISCELL
  mstr_standard tap *
  page13_i234
#ISCELL
  mstr_standard offpage *
  page13_i235
#ISCELL
  mstr_standard tap *
  page13_i236
#ISCELL
  mstr_standard tap *
  page13_i237
#ISCELL
  mstr_standard tap *
  page13_i238
#ISCELL
  mstr_standard tap *
  page13_i239
#ISCELL
  mstr_standard tap *
  page13_i240
#ISCELL
  mstr_standard tap *
  page13_i241
#ISCELL
  mstr_standard tap *
  page13_i242
#ISCELL
  mstr_standard tap *
  page13_i243
#ISCELL
  mstr_standard tap *
  page13_i244
#ISCELL
  mstr_standard tap *
  page13_i245
#ISCELL
  mstr_standard tap *
  page13_i246
#ISCELL
  mstr_standard tap *
  page13_i247
#ISCELL
  mstr_standard tap *
  page13_i248
#ISCELL
  mstr_standard tap *
  page13_i249
#ISCELL
  mstr_standard tap *
  page13_i250
#ISCELL
  mstr_standard tap *
  page13_i251
#ISCELL
  mstr_standard tap *
  page13_i252
#ISCELL
  mstr_standard tap *
  page13_i253
#ISCELL
  mstr_standard tap *
  page13_i254
#ISCELL
  mstr_standard tap *
  page13_i255
#ISCELL
  mstr_standard tap *
  page13_i256
#ISCELL
  mstr_standard tap *
  page13_i257
#ISCELL
  mstr_standard tap *
  page13_i258
#ISCELL
  mstr_standard tap *
  page13_i259
#ISCELL
  mstr_standard tap *
  page13_i260
#ISCELL
  mstr_standard tap *
  page13_i261
#ISCELL
  mstr_standard tap *
  page13_i262
#ISCELL
  mstr_standard tap *
  page13_i263
#ISCELL
  mstr_standard tap *
  page13_i264
#ISCELL
  mstr_standard tap *
  page13_i265
#ISCELL
  mstr_standard tap *
  page13_i266
#ISCELL
  mstr_standard tap *
  page13_i267
#ISCELL
  mstr_standard tap *
  page13_i268
#ISCELL
  mstr_standard tap *
  page13_i269
#ISCELL
  mstr_standard tap *
  page13_i270
#ISCELL
  mstr_standard tap *
  page13_i271
#ISCELL
  mstr_standard tap *
  page13_i272
#ISCELL
  mstr_standard tap *
  page13_i273
#ISCELL
  mstr_standard tap *
  page13_i274
#ISCELL
  mstr_standard tap *
  page13_i275
#ISCELL
  mstr_standard tap *
  page13_i276
#ISCELL
  mstr_standard tap *
  page13_i277
#ISCELL
  mstr_standard tap *
  page13_i278
#ISCELL
  mstr_standard tap *
  page13_i279
#ISCELL
  mstr_standard tap *
  page13_i280
#ISCELL
  mstr_standard tap *
  page13_i281
#ISCELL
  standard offpage *
  page13_i282
#ISCELL
  standard offpage *
  page13_i283
#ISCELL
  standard offpage *
  page13_i284
#ISCELL
  standard offpage *
  page13_i285
#ISCELL
  mstr_standard tap *
  page13_i286
#ISCELL
  mstr_standard tap *
  page13_i287
#ISCELL
  mstr_standard tap *
  page13_i288
#ISCELL
  mstr_standard tap *
  page13_i289
#ISCELL
  mstr_standard tap *
  page13_i290
#ISCELL
  mstr_standard tap *
  page13_i291
#ISCELL
  mstr_standard tap *
  page13_i292
#ISCELL
  mstr_standard tap *
  page13_i293
#ISCELL
  mstr_standard tap *
  page13_i294
#ISCELL
  mstr_standard tap *
  page13_i295
#ISCELL
  mstr_standard tap *
  page13_i296
#ISCELL
  mstr_standard tap *
  page13_i297
#ISCELL
  mstr_standard tap *
  page13_i298
#ISCELL
  mstr_standard tap *
  page13_i299
#ISCELL
  mstr_standard tap *
  page13_i300
#ISCELL
  mstr_standard tap *
  page13_i301
#ISCELL
  standard offpage *
  page13_i302
#ISCELL
  standard offpage *
  page13_i303
#ISCELL
  standard offpage *
  page13_i304
#ISCELL
  standard offpage *
  page13_i305
#ISCELL
  standard offpage *
  page13_i306
#ISCELL
  standard offpage *
  page13_i307
#ISCELL
  standard offpage *
  page13_i308
#ISCELL
  mstr_standard offpage *
  page13_i309
#ISCELL
  standard offpage *
  page13_i310
#ISCELL
  standard offpage *
  page13_i311
#ISCELL
  standard offpage *
  page13_i312
#ISCELL
  standard offpage *
  page13_i313
#CELL
  pure_quanta q_res *
  page13_i314
#ISCELL
  mstr_standard offpage *
  page13_i315
#ISCELL
  standard offpage *
  page13_i316
